# BASEBOARD_FAB2 (Tioga Pass) — schematic netlist excerpt (pin names and nets, part order shuffled) for the footprints in the layout excerpt that follows; sources: Cadence DE-HDL packaged netlist, KiCad conversion of Wiwynn_Tioga_Pass_MB.brd

C5A3  CAP_A  47UF 4V 20% X5R  pkg 0603V  page 220 : A = PVDDQ_DEF ; B = GND

(kicad_pcb
	(version 20260206)
	(generator "pcbnew")
	(generator_version "10.0")
	(general
		(thickness 1.6)
		(legacy_teardrops no)
	)
	(paper "A4")
	(title_block
		(title "Wiwynn_Tioga_Pass_MB.brd")
		(comment 1 "Tioga Pass / footprints 1699-1699 of 4770")
	)
	(layers
		(0 "F.Cu" signal "TOP")
		(4 "In1.Cu" signal "L2GND")
		(6 "In2.Cu" signal "L3")
		(8 "In3.Cu" signal "L4GND")
		(10 "In4.Cu" signal "L5")
		(12 "In5.Cu" signal "L6GND")
		(14 "In6.Cu" signal "L7VCC")
		(16 "In7.Cu" signal "L8VCC")
		(18 "In8.Cu" signal "L9GND")
		(20 "In9.Cu" signal "L10")
		(22 "In10.Cu" signal "L11GND")
		(24 "In11.Cu" signal "L12")
		(26 "In12.Cu" signal "L13GND")
		(2 "B.Cu" signal "BOTTOM")
		(9 "F.Adhes" user "F.Adhesive")
		(11 "B.Adhes" user "B.Adhesive")
		(13 "F.Paste" user "Package Geometry/Pastemask Top")
		(15 "B.Paste" user "Package Geometry/Pastemask Bottom")
		(5 "F.SilkS" user "Ref Des/Silkscreen Top")
		(7 "B.SilkS" user "Ref Des/Silkscreen Bottom")
		(1 "F.Mask" user "Board Geometry/Soldermask Top")
		(3 "B.Mask" user "Board Geometry/Soldermask Bottom")
		(17 "Dwgs.User" user "User.Drawings")
		(19 "Cmts.User" user "User.Comments")
		(21 "Eco1.User" user "User.Eco1")
		(23 "Eco2.User" user "User.Eco2")
		(25 "Edge.Cuts" user "Board Geometry/Outline")
		(27 "Margin" user)
		(31 "F.CrtYd" user "Package Geometry/Place Bound Top")
		(29 "B.CrtYd" user "Package Geometry/Place Bound Bottom")
		(35 "F.Fab" user "Ref Des/Assembly Top")
		(33 "B.Fab" user "Ref Des/Assembly Bottom")
	)
	(footprint ""
		(layer "F.Cu")
		(at 252.1585 -149.8092 -90)
		(property "Reference" "C5A3"
			(at 1.848866 0.752348 270)
			(unlocked yes)
			(layer "F.SilkS")
			(effects
				(font
					(size 1.27 0.9652)
					(thickness 0.1524)
				)
			)
		)
		(property "Value" ""
			(at 0 0 270)
			(layer "F.Fab")
			(effects
				(font
					(size 1.27 1.27)
				)
			)
		)
		(duplicate_pad_numbers_are_jumpers no)
		(fp_rect
			(start -0.500126 1.598422)
			(end 0.500126 -0.201422)
			(stroke
				(width 0)
				(type default)
			)
			(fill no)
			(layer "F.CrtYd")
		)
		(fp_line
			(start -0.500126 1.598422)
			(end -0.500126 -0.201422)
			(stroke
				(width 0.1)
				(type default)
			)
			(layer "F.Fab")
		)
		(fp_line
			(start 0.500126 1.598422)
			(end -0.500126 1.598422)
			(stroke
				(width 0.1)
				(type default)
			)
			(layer "F.Fab")
		)
		(fp_line
			(start -0.500126 -0.201422)
			(end 0.500126 -0.201422)
			(stroke
				(width 0.1)
				(type default)
			)
			(layer "F.Fab")
		)
		(fp_line
			(start 0.500126 -0.201422)
			(end 0.500126 1.598422)
			(stroke
				(width 0.1)
				(type default)
			)
			(layer "F.Fab")
		)
		(pad "1" smd rect
			(at 0 0 180)
			(size 0.889 0.9906)
			(layers "F.Cu" "F.Mask" "F.Paste")
			(net "PVDDQ_DEF")
		)
		(pad "2" smd rect
			(at 0 1.397 180)
			(size 0.889 0.9906)
			(layers "F.Cu" "F.Mask" "F.Paste")
			(net "GND")
		)
		(zone
			(layer "F.Cu")
			(hatch none 0.5)
			(connect_pads
				(clearance 0)
			)
			(min_thickness 0.25)
			(keepout
				(tracks allowed)
				(vias not_allowed)
				(pads allowed)
				(copperpour not_allowed)
				(footprints allowed)
			)
			(placement
				(enabled no)
				(sheetname "")
			)
			(fill
				(thermal_gap 0.5)
				(thermal_bridge_width 0.5)
				(island_removal_mode 0)
			)
			(polygon
				(pts
					(xy 251.206 -150.3045) (xy 251.206 -149.3139) (xy 251.714 -149.3139) (xy 251.714 -150.3045)
				)
			)
		)
		(zone
			(layer "F.Cu")
			(hatch none 0.5)
			(connect_pads
				(clearance 0)
			)
			(min_thickness 0.25)
			(keepout
				(tracks not_allowed)
				(vias allowed)
				(pads allowed)
				(copperpour not_allowed)
				(footprints allowed)
			)
			(placement
				(enabled no)
				(sheetname "")
			)
			(fill
				(thermal_gap 0.5)
				(thermal_bridge_width 0.5)
				(island_removal_mode 0)
			)
			(polygon
				(pts
					(xy 251.206 -150.3045) (xy 251.206 -149.3139) (xy 251.714 -149.3139) (xy 251.714 -150.3045)
				)
			)
		)
	)
)
